# S9S_MB_2U (Grand Teton) — schematic netlist excerpt (pin names and nets, part order shuffled) for the footprints in the layout excerpt that follows; sources: Cadence DE-HDL packaged netlist, KiCad conversion of 03242023_DA0F0TMBIJ0_F0T_Motherboard_J_brd_V01_OCP.brd

C434  Q_CAP  22UF 4V 20% X6S  pkg C0402  page 77 : A = PVCCINFAON_CPU1 ; B = GND
C990  Q_CAP  10UF 6.3V 20% X6S  pkg C0402  page 74 : A = PVCCIN_CPU0 ; B = GND

(kicad_pcb
	(version 20260206)
	(generator "pcbnew")
	(generator_version "10.0")
	(general
		(thickness 1.6)
		(legacy_teardrops no)
	)
	(paper "A4")
	(title_block
		(title "03242023_DA0F0TMBIJ0_F0T_Motherboard_J_brd_V01_OCP.brd")
		(comment 1 "Grand Teton / footprints 3290-3291 of 6105")
	)
	(layers
		(0 "F.Cu" signal "TOP")
		(4 "In1.Cu" signal "GND")
		(6 "In2.Cu" signal "IN1")
		(8 "In3.Cu" signal "GND1")
		(10 "In4.Cu" signal "IN2")
		(12 "In5.Cu" signal "GND2")
		(14 "In6.Cu" signal "IN3")
		(16 "In7.Cu" signal "GND3")
		(18 "In8.Cu" signal "VCC")
		(20 "In9.Cu" signal "VCC1")
		(22 "In10.Cu" signal "GND4")
		(24 "In11.Cu" signal "IN4")
		(26 "In12.Cu" signal "GND5")
		(28 "In13.Cu" signal "IN5")
		(30 "In14.Cu" signal "GND6")
		(32 "In15.Cu" signal "IN6")
		(34 "In16.Cu" signal "GND7")
		(2 "B.Cu" signal "BOTTOM")
		(9 "F.Adhes" user "F.Adhesive")
		(11 "B.Adhes" user "B.Adhesive")
		(13 "F.Paste" user "Package Geometry/Pastemask Top")
		(15 "B.Paste" user "Package Geometry/Pastemask Bottom")
		(5 "F.SilkS" user "Ref Des/Silkscreen Top")
		(7 "B.SilkS" user "Ref Des/Silkscreen Bottom")
		(1 "F.Mask" user "Board Geometry/Soldermask Top")
		(3 "B.Mask" user "Board Geometry/Soldermask Bottom")
		(17 "Dwgs.User" user "User.Drawings")
		(19 "Cmts.User" user "User.Comments")
		(21 "Eco1.User" user "User.Eco1")
		(23 "Eco2.User" user "User.Eco2")
		(25 "Edge.Cuts" user "Board Geometry/Outline")
		(27 "Margin" user)
		(31 "F.CrtYd" user "Package Geometry/Place Bound Top")
		(29 "B.CrtYd" user "Package Geometry/Place Bound Bottom")
		(35 "F.Fab" user "Ref Des/Assembly Top")
		(33 "B.Fab" user "Ref Des/Assembly Bottom")
	)
	(footprint ""
		(layer "F.Cu")
		(at 354.251514 -255.053846 90)
		(property "Reference" "C990"
			(at 0 0 90)
			(layer "F.SilkS")
			(hide yes)
			(effects
				(font
					(size 1.27 1.27)
				)
			)
		)
		(property "Value" ""
			(at 0 0 90)
			(layer "F.Fab")
			(effects
				(font
					(size 1.27 1.27)
				)
			)
		)
		(duplicate_pad_numbers_are_jumpers no)
		(fp_line
			(start 0.7874 -0.4064)
			(end 0.7874 0.4064)
			(stroke
				(width 0.1524)
				(type default)
			)
			(layer "F.SilkS")
		)
		(fp_line
			(start -0.7874 -0.4064)
			(end 0.7874 -0.4064)
			(stroke
				(width 0.1524)
				(type default)
			)
			(layer "F.SilkS")
		)
		(fp_line
			(start 0.7874 0.4064)
			(end -0.7874 0.4064)
			(stroke
				(width 0.1524)
				(type default)
			)
			(layer "F.SilkS")
		)
		(fp_line
			(start -0.7874 0.4064)
			(end -0.7874 -0.4064)
			(stroke
				(width 0.1524)
				(type default)
			)
			(layer "F.SilkS")
		)
		(fp_line
			(start -0.12065 -0.305054)
			(end -0.12065 -0.2794)
			(stroke
				(width 0.1)
				(type default)
			)
			(layer "F.Fab")
		)
		(fp_line
			(start -0.67945 -0.305054)
			(end -0.12065 -0.305054)
			(stroke
				(width 0.1)
				(type default)
			)
			(layer "F.Fab")
		)
		(fp_line
			(start 0.67945 -0.3048)
			(end 0.67945 0.3048)
			(stroke
				(width 0.1)
				(type default)
			)
			(layer "F.Fab")
		)
		(fp_line
			(start 0.12065 -0.3048)
			(end 0.67945 -0.3048)
			(stroke
				(width 0.1)
				(type default)
			)
			(layer "F.Fab")
		)
		(fp_line
			(start 0.12065 -0.2794)
			(end 0.12065 -0.3048)
			(stroke
				(width 0.1)
				(type default)
			)
			(layer "F.Fab")
		)
		(fp_line
			(start -0.12065 -0.2794)
			(end 0.12065 -0.2794)
			(stroke
				(width 0.1)
				(type default)
			)
			(layer "F.Fab")
		)
		(fp_line
			(start 0.120396 0.2794)
			(end -0.12065 0.2794)
			(stroke
				(width 0.1)
				(type default)
			)
			(layer "F.Fab")
		)
		(fp_line
			(start -0.12065 0.2794)
			(end -0.12065 0.3048)
			(stroke
				(width 0.1)
				(type default)
			)
			(layer "F.Fab")
		)
		(fp_line
			(start 0.67945 0.3048)
			(end 0.120396 0.3048)
			(stroke
				(width 0.1)
				(type default)
			)
			(layer "F.Fab")
		)
		(fp_line
			(start 0.120396 0.3048)
			(end 0.120396 0.2794)
			(stroke
				(width 0.1)
				(type default)
			)
			(layer "F.Fab")
		)
		(fp_line
			(start -0.12065 0.3048)
			(end -0.67945 0.3048)
			(stroke
				(width 0.1)
				(type default)
			)
			(layer "F.Fab")
		)
		(fp_line
			(start -0.67945 0.3048)
			(end -0.67945 -0.305054)
			(stroke
				(width 0.1)
				(type default)
			)
			(layer "F.Fab")
		)
		(pad "1" smd circle
			(at -0.40005 0 90)
			(size 0 0)
			(layers "F.Cu" "F.Mask" "F.Paste")
			(net "PVCCIN_CPU0")
		)
		(pad "2" smd circle
			(at 0.40005 0 90)
			(size 0 0)
			(layers "F.Cu" "F.Mask" "F.Paste")
			(net "GND")
		)
	)
	(footprint ""
		(layer "F.Cu")
		(at 116.561616 -238.162592 90)
		(property "Reference" "C434"
			(at 0 0 90)
			(layer "F.SilkS")
			(hide yes)
			(effects
				(font
					(size 1.27 1.27)
				)
			)
		)
		(property "Value" ""
			(at 0 0 90)
			(layer "F.Fab")
			(effects
				(font
					(size 1.27 1.27)
				)
			)
		)
		(duplicate_pad_numbers_are_jumpers no)
		(fp_line
			(start 0.7874 -0.4064)
			(end 0.7874 0.4064)
			(stroke
				(width 0.1524)
				(type default)
			)
			(layer "F.SilkS")
		)
		(fp_line
			(start -0.7874 -0.4064)
			(end 0.7874 -0.4064)
			(stroke
				(width 0.1524)
				(type default)
			)
			(layer "F.SilkS")
		)
		(fp_line
			(start 0.7874 0.4064)
			(end -0.7874 0.4064)
			(stroke
				(width 0.1524)
				(type default)
			)
			(layer "F.SilkS")
		)
		(fp_line
			(start -0.7874 0.4064)
			(end -0.7874 -0.4064)
			(stroke
				(width 0.1524)
				(type default)
			)
			(layer "F.SilkS")
		)
		(fp_line
			(start -0.12065 -0.305054)
			(end -0.12065 -0.2794)
			(stroke
				(width 0.1)
				(type default)
			)
			(layer "F.Fab")
		)
		(fp_line
			(start -0.67945 -0.305054)
			(end -0.12065 -0.305054)
			(stroke
				(width 0.1)
				(type default)
			)
			(layer "F.Fab")
		)
		(fp_line
			(start 0.67945 -0.3048)
			(end 0.67945 0.3048)
			(stroke
				(width 0.1)
				(type default)
			)
			(layer "F.Fab")
		)
		(fp_line
			(start 0.12065 -0.3048)
			(end 0.67945 -0.3048)
			(stroke
				(width 0.1)
				(type default)
			)
			(layer "F.Fab")
		)
		(fp_line
			(start 0.12065 -0.2794)
			(end 0.12065 -0.3048)
			(stroke
				(width 0.1)
				(type default)
			)
			(layer "F.Fab")
		)
		(fp_line
			(start -0.12065 -0.2794)
			(end 0.12065 -0.2794)
			(stroke
				(width 0.1)
				(type default)
			)
			(layer "F.Fab")
		)
		(fp_line
			(start 0.120396 0.2794)
			(end -0.12065 0.2794)
			(stroke
				(width 0.1)
				(type default)
			)
			(layer "F.Fab")
		)
		(fp_line
			(start -0.12065 0.2794)
			(end -0.12065 0.3048)
			(stroke
				(width 0.1)
				(type default)
			)
			(layer "F.Fab")
		)
		(fp_line
			(start 0.67945 0.3048)
			(end 0.120396 0.3048)
			(stroke
				(width 0.1)
				(type default)
			)
			(layer "F.Fab")
		)
		(fp_line
			(start 0.120396 0.3048)
			(end 0.120396 0.2794)
			(stroke
				(width 0.1)
				(type default)
			)
			(layer "F.Fab")
		)
		(fp_line
			(start -0.12065 0.3048)
			(end -0.67945 0.3048)
			(stroke
				(width 0.1)
				(type default)
			)
			(layer "F.Fab")
		)
		(fp_line
			(start -0.67945 0.3048)
			(end -0.67945 -0.305054)
			(stroke
				(width 0.1)
				(type default)
			)
			(layer "F.Fab")
		)
		(pad "1" smd circle
			(at -0.40005 0 90)
			(size 0 0)
			(layers "F.Cu" "F.Mask" "F.Paste")
			(net "PVCCINFAON_CPU1")
		)
		(pad "2" smd circle
			(at 0.40005 0 90)
			(size 0 0)
			(layers "F.Cu" "F.Mask" "F.Paste")
			(net "GND")
		)
	)
)
